FILE_TYPE = CONNECTIVITY;
{Allegro Design Entry HDL 16.6-p007 (v16-6-112F) 10/10/2012}
"PAGE_NUMBER" = 170;
0"NC";
1"P3V3_STBY\g";
2"GND\g";
3"P3V3_STBY\g";
4"GND\g";
5"P3V3_STBY\g";
6"P3V3_STBY\g";
7"GND\g";
8"GND\g";
9"P3V3_STBY\g";
10"GND\g";
11"P3V3_STBY\g";
12"P3V3_STBY\g";
13"P3V3_STBY\g";
14"GND\g";
15"P3V3_STBY\g";
16"GND\g";
17"P3V3_STBY\g";
18"GND\g";
19"GND\g";
20"P3V3_STBY\g";
21"P3V3_STBY\g";
22"IRQ_SML1_PMBUS_ALERT_N";
23"FM_PMBUS_ALERT_BUF_EN";
24"FM_PMBUS_ALERT_BUF_EN_N";
25"FM_FAST_PROCHOT_THROTTLE_DLY_N";
26"FM_FAST_PROCHOT_EN";
27"FM_FAST_PROCHOT_THROTTLE_DLY_BUF_N";
28"FM_THROTTLE_R1_N";
29"FM_THROTTLE_N";
30"FM_FAST_PROCHOT_EN_N";
31"IRQ_SML1_PMBUS_ALERT_BUF_N";
32"IRQ_FORCE_NM_THROTTLE_R_N";
33"FM_FAST_PROCHOT_THROTTLE_IN_N";
34"IRQ_UV_DETECT_N";
35"FM_HSC_TIMER_EXP_N";
36"IRQ_FORCE_NM_THROTTLE_N";
37"FM_FAST_PROCHOT_AND_OUT_0_N";
38"FM_FAST_PROCHOT_AND_OUT_1_N";
39"FM_OC_DETECT_N";
%"TTL08"
"1","(-1175,4375)","0","mstr_ttl","I10";
;
CDS_SEC"4"
PART_NUMBER"D90404-001"
LOCATION"U8E1"
MATERIAL"IC"
VALUE"74LVC08A"
POWER_GROUP"VCC=P3V3_STBY;GND=GND;TH=GND"
SEC_TYPE"QFN15"
BOM_COST"FAST_PROCHOT"
SEC"4"
ROOM"FAST_PROCHOT"
PACK_TYPE"QFN15"
CDS_LOCATION"U8E1"
CDS_LIB"mstr_ttl";
"A <SIZE-1..0>"
$PN"1"36;
"B <SIZE-1..0>"
$PN"2"39;
"Y <SIZE-1..0>"
$PN"3"37;
%"TTL08"
"1","(-1175,3650)","0","mstr_ttl","I11";
;
CDS_SEC"3"
MATERIAL"IC"
PART_NUMBER"D90404-001"
POWER_GROUP"VCC=P3V3_STBY;GND=GND;TH=GND"
VALUE"74LVC08A"
LOCATION"U8E1"
SEC_TYPE"QFN15"
BOM_COST"FAST_PROCHOT"
SEC"3"
CDS_LOCATION"U8E1"
ROOM"FAST_PROCHOT"
PACK_TYPE"QFN15"
CDS_LIB"mstr_ttl";
"A <SIZE-1..0>"
$PN"4"34;
"B <SIZE-1..0>"
$PN"5"35;
"Y <SIZE-1..0>"
$PN"6"38;
%"TTL08"
"1","(-25,4075)","0","mstr_ttl","I12";
;
CDS_SEC"1"
VALUE"74LVC08A"
LOCATION"U8E1"
MATERIAL"IC"
PART_NUMBER"D90404-001"
POWER_GROUP"VCC=P3V3_STBY;GND=GND;TH=GND"
BOM_COST"FAST_PROCHOT"
SEC"1"
SEC_TYPE"QFN15"
PACK_TYPE"QFN15"
ROOM"FAST_PROCHOT"
CDS_LOCATION"U8E1"
CDS_LIB"mstr_ttl";
"A <SIZE-1..0>"
$PN"12"37;
"B <SIZE-1..0>"
$PN"13"38;
"Y <SIZE-1..0>"
$PN"11"33;
%"RES"
"2","(-2125,5250)","0","mstr_discrete","I2";
;
CDS_SEC"1"
PART_NUMBER"G21796-072"
WATTAGE"1/16W"
MATERIAL"CHIP"
TOLERANCE"1%"
PACK_TYPE"0402"
LOCATION"R2P3"
VALUE"4.75K"
SEC_TYPE"0402"
BOM_COST"FAST_PROCHOT"
SEC"1"
ROOM"FAST_PROCHOT"
CDS_LOCATION"R2P3"
CDS_LIB"mstr_discrete";
"A"
$PN"1"1;
"B"
$PN"2"32;
%"TTL1G126_A"
"1","(-2525,2525)","0","mstr_ttl","I20";
;
CDS_SEC"1"
LOCATION"U1R2"
VALUE"74HC1G126"
MATERIAL"IC"
PART_NUMBER"A79322-001"
POWER_GROUP"VCC=P3V3_STBY;GND=GND;"
PACK_TYPE"SOT"
ROOM"FAST_PROCHOT"
CDS_LOCATION"U1R2"
SEC"1"
BOM_COST"FAST_PROCHOT"
SEC_TYPE"SOT"
CDS_LIB"mstr_ttl";
"OE"
$PN"1"26;
"Y"
$PN"4"27;
"A"
$PN"2"25;
%"P3V3_STBY"
"1","(-2125,5475)","0","mstr_symbols","I3";
;
VOLTAGE"3.3V"
SIZE"1B"
CDS_LIB"mstr_symbols"
BODY_TYPE"PLUMBING"
HDL_POWER"P3V3_STBY";
"G\NAC"1;
%"CAP_A"
"1","(-5150,1325)","0","dev_discrete","I30";
;
LOCATION"C1R27"
PART_NUMBER"A36096-030"
VALUE"0.1UF"
TOLERANCE"10%"
PACK_TYPE"0402V"
VOLTAGE"16V"
MATERIAL"X7R"
CDS_LIB"dev_discrete"
CDS_SEC"1"
ROOM"FAST_PROCHOT"
CDS_LOCATION"C1R27"
SEC_TYPE"0402V"
SEC"1"
BOM_COST"FAST_PROCHOT";
"B"
$PN"2"2;
"A"
$PN"1"3;
%"GND"
"1","(-5150,1050)","0","mstr_symbols","I31";
;
VOLTAGE"0.0V"
CDS_LIB"mstr_symbols"
SIZE"1B"
BODY_TYPE"PLUMBING"
HDL_POWER"GND";
"A\NAC"2;
%"P3V3_STBY"
"1","(-5150,1575)","0","mstr_symbols","I32";
;
VOLTAGE"3.3V"
CDS_LIB"mstr_symbols"
SIZE"1B"
BODY_TYPE"PLUMBING"
HDL_POWER"P3V3_STBY";
"G\NAC"3;
%"CAP_A"
"1","(-200,4775)","0","dev_discrete","I33";
;
LOCATION"C8D2"
VALUE"0.1UF"
VOLTAGE"16V"
TOLERANCE"10%"
MATERIAL"X7R"
PART_NUMBER"A36096-030"
PACK_TYPE"0402V"
CDS_LOCATION"C8D2"
ROOM"FAST_PROCHOT"
CDS_SEC"1"
SEC_TYPE"0402V"
BOM_COST"FAST_PROCHOT"
SEC"1"
CDS_LIB"dev_discrete";
"B"
$PN"2"4;
"A"
$PN"1"5;
%"GND"
"1","(-200,4500)","0","mstr_symbols","I34";
;
SIZE"1B"
CDS_LIB"mstr_symbols"
VOLTAGE"0.0V"
BODY_TYPE"PLUMBING"
HDL_POWER"GND";
"A\NAC"4;
%"P3V3_STBY"
"1","(-200,5025)","0","mstr_symbols","I35";
;
SIZE"1B"
VOLTAGE"3.3V"
CDS_LIB"mstr_symbols"
BODY_TYPE"PLUMBING"
HDL_POWER"P3V3_STBY";
"G\NAC"5;
%"TTL1G126_A"
"1","(-3500,4775)","0","mstr_ttl","I38";
;
CDS_SEC"1"
PART_NUMBER"A79322-001"
VALUE"74HC1G126"
MATERIAL"IC"
LOCATION"U8D5"
POWER_GROUP"VCC=P3V3_STBY;GND=GND;"
CDS_LIB"mstr_ttl"
PACK_TYPE"SOT"
ROOM"PROC_SIDEBAND"
BOM_COST"PROC_SIDEBAND"
SEC_TYPE"SOT"
SEC"1"
CDS_LOCATION"U8D5";
"OE"
$PN"1"23;
"Y"
$PN"4"31;
"A"
$PN"2"22;
%"P3V3_STBY"
"1","(-1350,5350)","0","mstr_symbols","I39";
;
SIZE"1B"
CDS_LIB"mstr_symbols"
VOLTAGE"3.3V"
BODY_TYPE"PLUMBING"
HDL_POWER"P3V3_STBY";
"G\NAC"6;
%"TTL1G07_A"
"1","(-2400,4775)","0","mstr_ttl","I4";
;
LOCATION"U8D3"
MATERIAL"IC"
PART_NUMBER"C88419-001"
VALUE"74LVC1G07"
POWER_GROUP"VCC=P3V3_STBY;GND=GND"
BOM_COST"FAST_PROCHOT"
CDS_LIB"mstr_ttl"
CDS_SEC"1"
$SEC"1"
CDS_LOCATION"U8D3"
ROOM"FAST_PROCHOT"
PACK_TYPE"SOP";
"Y"
$PN"4"32;
"A"
$PN"2"31;
%"CAP_A"
"1","(-1350,5100)","0","dev_discrete","I40";
;
VALUE"0.1UF"
LOCATION"C8E2"
VOLTAGE"16V"
TOLERANCE"10%"
MATERIAL"X7R"
PART_NUMBER"A36096-030"
PACK_TYPE"0402V"
CDS_SEC"1"
SEC_TYPE"0402V"
ROOM"PROC_SIDEBAND"
SEC"1"
BOM_COST"PROC_SIDEBAND"
CDS_LOCATION"C8E2"
CDS_LIB"dev_discrete";
"B"
$PN"2"7;
"A"
$PN"1"6;
%"GND"
"1","(-1350,4825)","0","mstr_symbols","I41";
;
SIZE"1B"
CDS_LIB"mstr_symbols"
VOLTAGE"0.0V"
BODY_TYPE"PLUMBING"
HDL_POWER"GND";
"A\NAC"7;
%"CAP"
"1","(-3700,4250)","0","mstr_discrete","I42";
;
CDS_SEC"1"
PACK_TYPE"0402LF"
VOLTAGE"50V"
TOLERANCE"10%"
MATERIAL"EMPTY"
LOCATION"C8D3"
VALUE"470PF"
PART_NUMBER"A36096-049"
SEC_TYPE"0402LF"
SEC"1"
CDS_LIB"mstr_discrete"
ROOM"PROC_SIDEBAND"
BOM_COST"PROC_SIDEBAND"
CDS_LOCATION"C8D3";
"A"
$PN"1"22;
"B"
$PN"2"8;
%"GND"
"1","(-3700,3950)","0","mstr_symbols","I43";
;
VOLTAGE"0.0V"
CDS_LIB"mstr_symbols"
SIZE"1B"
BODY_TYPE"PLUMBING"
HDL_POWER"GND";
"A\NAC"8;
%"TTL1G07_A"
"1","(-1225,2525)","0","mstr_ttl","I46";
;
CDS_SEC"1"
POWER_GROUP"VCC=P3V3_STBY;GND=GND"
PART_NUMBER"C88419-001"
MATERIAL"IC"
VALUE"74LVC1G07"
LOCATION"U1R1"
BOM_COST"FAST_PROCHOT"
SEC_TYPE"SOP"
SEC"1"
CDS_LOCATION"U1R1"
PACK_TYPE"SOP"
ROOM"FAST_PROCHOT"
CDS_LIB"mstr_ttl";
"Y"
$PN"4"28;
"A"
$PN"2"27;
%"P3V3_STBY"
"1","(-1600,1950)","0","mstr_symbols","I48";
;
VOLTAGE"3.3V"
SIZE"1B"
CDS_LIB"mstr_symbols"
BODY_TYPE"PLUMBING"
HDL_POWER"P3V3_STBY";
"G\NAC"9;
%"CAP_A"
"1","(-1600,1700)","0","dev_discrete","I49";
;
LOCATION"C1R28"
PART_NUMBER"A36096-030"
VALUE"0.1UF"
TOLERANCE"10%"
PACK_TYPE"0402V"
VOLTAGE"16V"
MATERIAL"X7R"
CDS_LIB"dev_discrete"
ROOM"FAST_PROCHOT"
CDS_SEC"1"
CDS_LOCATION"C1R28"
SEC"1"
SEC_TYPE"0402V"
BOM_COST"FAST_PROCHOT";
"B"
$PN"2"10;
"A"
$PN"1"9;
%"GND"
"1","(-1600,1425)","0","mstr_symbols","I50";
;
VOLTAGE"0.0V"
CDS_LIB"mstr_symbols"
SIZE"1B"
BODY_TYPE"PLUMBING"
HDL_POWER"GND";
"A\NAC"10;
%"RES"
"1","(-475,2525)","0","mstr_discrete","I51";
;
CDS_SEC"1"
WATTAGE"1/16W"
TOLERANCE"5%"
LOCATION"R1R8"
PACK_TYPE"0402"
VALUE"0.0"
MATERIAL"CHIP"
PART_NUMBER"G21497-005"
SEC_TYPE"0402"
SEC"1"
CDS_LOCATION"R1R8"
BOM_COST"PROC_SIDEBAND"
CDS_LIB"mstr_discrete"
ROOM"PROC_SIDEBAND";
"B"
$PN"2"29;
"A"
$PN"1"28;
%"P3V3_STBY"
"1","(-3825,5475)","0","mstr_symbols","I53";
;
VOLTAGE"3.3V"
SIZE"1B"
CDS_LIB"mstr_symbols"
BODY_TYPE"PLUMBING"
HDL_POWER"P3V3_STBY";
"G\NAC"11;
%"RES"
"2","(-3450,2075)","0","mstr_discrete","I54";
;
CDS_SEC"1"
PART_NUMBER"G21796-072"
PACK_TYPE"0402"
MATERIAL"CHIP"
TOLERANCE"1%"
LOCATION"R2T3"
VALUE"4.75K"
WATTAGE"1/16W"
CDS_LIB"mstr_discrete"
CDS_LOCATION"R2T3"
ROOM"FAST_PROCHOT"
SEC"1"
SEC_TYPE"0402"
BOM_COST"FAST_PROCHOT";
"A"
$PN"1"12;
"B"
$PN"2"30;
%"P3V3_STBY"
"1","(-3450,2350)","0","mstr_symbols","I55";
;
CDS_LIB"mstr_symbols"
VOLTAGE"3.3V"
SIZE"1B"
BODY_TYPE"PLUMBING"
HDL_POWER"P3V3_STBY";
"G\NAC"12;
%"RES"
"2","(-4150,5100)","0","mstr_discrete","I56";
;
CDS_SEC"1"
TOLERANCE"1%"
WATTAGE"1/16W"
MATERIAL"CHIP"
PACK_TYPE"0402"
VALUE"4.75K"
LOCATION"R2P5"
PART_NUMBER"G21796-072"
CDS_LOCATION"R2P5"
BOM_COST"PROC_SIDEBAND"
SEC_TYPE"0402"
SEC"1"
ROOM"PROC_SIDEBAND"
CDS_LIB"mstr_discrete";
"A"
$PN"1"11;
"B"
$PN"2"23;
%"FET_N"
"8","(-4150,4225)","0","mstr_discrete","I58";
;
CDS_SEC"1"
MATERIAL"FET"
PART_NUMBER"C79254-001"
VALUE"2N7002"
LOCATION"Q2P1"
CDS_LIB"mstr_discrete"
PACK_TYPE"SOT23LF"
ROOM"PROC_SIDEBAND"
CDS_LOCATION"Q2P1"
SEC"1"
BOM_COST"PROC_SIDEBAND"
SEC_TYPE"SOT23LF";
"GATE"
$PN"1"24;
"DRN"
$PN"3"23;
"SRC"
$PN"2"14;
%"P3V3_STBY"
"1","(-5100,3600)","0","mstr_symbols","I6";
;
VOLTAGE"3.3V"
SIZE"1B"
CDS_LIB"mstr_symbols"
BODY_TYPE"PLUMBING"
HDL_POWER"P3V3_STBY";
"G\NAC"13;
%"GND"
"1","(-4150,3900)","0","mstr_symbols","I60";
;
VOLTAGE"0.0V"
CDS_LIB"mstr_symbols"
SIZE"1B"
BODY_TYPE"PLUMBING"
HDL_POWER"GND";
"A\NAC"14;
%"RES"
"2","(-4600,4350)","0","mstr_discrete","I61";
;
CDS_SEC"1"
PACK_TYPE"0402"
MATERIAL"CHIP"
WATTAGE"1/16W"
TOLERANCE"1%"
LOCATION"R2P13"
VALUE"4.75K"
PART_NUMBER"G21796-072"
CDS_LIB"mstr_discrete"
CDS_LOCATION"R2P13"
SEC"1"
ROOM"PROC_SIDEBAND"
SEC_TYPE"0402"
BOM_COST"PROC_SIDEBAND";
"A"
$PN"1"15;
"B"
$PN"2"24;
%"P3V3_STBY"
"1","(-4600,4575)","0","mstr_symbols","I62";
;
VOLTAGE"3.3V"
CDS_LIB"mstr_symbols"
SIZE"1B"
BODY_TYPE"PLUMBING"
HDL_POWER"P3V3_STBY";
"G\NAC"15;
%"RES"
"2","(-4525,3925)","0","mstr_discrete","I63";
;
CDS_SEC"1"
VALUE"1.00K"
PACK_TYPE"0402"
MATERIAL"EMPTY"
PART_NUMBER"G21796-026"
TOLERANCE"1%"
LOCATION"R2P11"
WATTAGE"1/16W"
SEC_TYPE"0402"
SEC"1"
CDS_LIB"mstr_discrete"
CDS_LOCATION"R2P11"
ROOM"PROC_SIDEBAND"
BOM_COST"PROC_SIDEBAND";
"A"
$PN"1"24;
"B"
$PN"2"16;
%"GND"
"1","(-4525,3700)","0","mstr_symbols","I64";
;
VOLTAGE"0.0V"
CDS_LIB"mstr_symbols"
SIZE"1B"
BODY_TYPE"PLUMBING"
HDL_POWER"GND";
"A\NAC"16;
%"RES"
"2","(-2950,2775)","0","mstr_discrete","I65";
;
CDS_SEC"1"
TOLERANCE"1%"
LOCATION"R9F3"
PART_NUMBER"G21796-072"
VALUE"4.75K"
PACK_TYPE"0402"
MATERIAL"CHIP"
WATTAGE"1/16W"
CDS_LIB"mstr_discrete"
SEC"1"
CDS_LOCATION"R9F3"
ROOM"PROC_SIDEBAND"
BOM_COST"PROC_SIDEBAND"
SEC_TYPE"0402";
"A"
$PN"1"17;
"B"
$PN"2"26;
%"P3V3_STBY"
"1","(-2950,3000)","0","mstr_symbols","I66";
;
VOLTAGE"3.3V"
CDS_LIB"mstr_symbols"
SIZE"1B"
BODY_TYPE"PLUMBING"
HDL_POWER"P3V3_STBY";
"G\NAC"17;
%"FET_N"
"8","(-2950,1900)","0","mstr_discrete","I67";
;
CDS_SEC"1"
LOCATION"Q8F2"
VALUE"2N7002"
MATERIAL"FET"
PART_NUMBER"C79254-001"
CDS_LIB"mstr_discrete"
PACK_TYPE"SOT23LF"
ROOM"PROC_SIDEBAND"
CDS_LOCATION"Q8F2"
SEC"1"
SEC_TYPE"SOT23LF"
BOM_COST"PROC_SIDEBAND";
"GATE"
$PN"1"30;
"DRN"
$PN"3"26;
"SRC"
$PN"2"18;
%"GND"
"1","(-2950,1575)","0","mstr_symbols","I68";
;
VOLTAGE"0.0V"
SIZE"1B"
CDS_LIB"mstr_symbols"
BODY_TYPE"PLUMBING"
HDL_POWER"GND";
"A\NAC"18;
%"GND"
"1","(-5100,3075)","0","mstr_symbols","I7";
;
VOLTAGE"0.0V"
SIZE"1B"
CDS_LIB"mstr_symbols"
BODY_TYPE"PLUMBING"
HDL_POWER"GND";
"A\NAC"19;
%"P3V3_STBY"
"1","(-3150,5475)","0","mstr_symbols","I70";
;
CDS_LIB"mstr_symbols"
SIZE"1B"
VOLTAGE"3.3V"
BODY_TYPE"PLUMBING"
HDL_POWER"P3V3_STBY";
"G\NAC"20;
%"RES"
"2","(-3150,5100)","0","mstr_discrete","I71";
;
CDS_SEC"1"
PART_NUMBER"G21796-072"
PACK_TYPE"0402"
MATERIAL"CHIP"
TOLERANCE"1%"
LOCATION"R8D26"
VALUE"4.75K"
WATTAGE"1/16W"
CDS_LIB"mstr_discrete"
ROOM"FAST_PROCHOT"
SEC_TYPE"0402"
BOM_COST"FAST_PROCHOT"
SEC"1"
CDS_LOCATION"R8D26";
"A"
$PN"1"20;
"B"
$PN"2"31;
%"P3V3_STBY"
"1","(-2025,3075)","0","mstr_symbols","I72";
;
VOLTAGE"3.3V"
SIZE"1B"
CDS_LIB"mstr_symbols"
BODY_TYPE"PLUMBING"
HDL_POWER"P3V3_STBY";
"G\NAC"21;
%"RES"
"2","(-2025,2850)","0","mstr_discrete","I73";
;
CDS_SEC"1"
MATERIAL"CHIP"
PACK_TYPE"0402"
TOLERANCE"1%"
LOCATION"R1R5"
VALUE"4.75K"
WATTAGE"1/16W"
PART_NUMBER"G21796-072"
CDS_LIB"mstr_discrete"
CDS_LOCATION"R1R5"
ROOM"FAST_PROCHOT"
SEC"1"
SEC_TYPE"0402"
BOM_COST"FAST_PROCHOT";
"A"
$PN"1"21;
"B"
$PN"2"27;
%"RES"
"1","(-1675,4775)","0","mstr_discrete","I74";
;
CDS_SEC"1"
PACK_TYPE"0402"
MATERIAL"CHIP"
PART_NUMBER"G21796-074"
LOCATION"R2P4"
WATTAGE"1/16W"
TOLERANCE"1%"
VALUE"33.2"
SEC"1"
SEC_TYPE"0402"
CDS_LIB"mstr_discrete"
CDS_LOCATION"R2P4";
"B"
$PN"2"36;
"A"
$PN"1"32;
%"RES"
"2","(-3825,5100)","0","mstr_discrete","I75";
;
CDS_SEC"1"
TOLERANCE"1%"
MATERIAL"CHIP"
PACK_TYPE"0402"
PART_NUMBER"G21796-072"
WATTAGE"1/16W"
VALUE"4.75K"
LOCATION"R2P8"
BOM_COST"PROC_SIDEBAND"
SEC_TYPE"0402"
SEC"1"
ROOM"PROC_SIDEBAND"
CDS_LIB"mstr_discrete"
CDS_LOCATION"R2P8";
"A"
$PN"1"11;
"B"
$PN"2"22;
%"CAP_A"
"1","(-5100,3350)","0","dev_discrete","I8";
;
LOCATION"C2P1"
VALUE"0.1UF"
MATERIAL"X7R"
TOLERANCE"10%"
PACK_TYPE"0402V"
VOLTAGE"16V"
PART_NUMBER"A36096-030"
CDS_LOCATION"C2P1"
CDS_LIB"dev_discrete"
CDS_SEC"1"
SEC"1"
ROOM"FAST_PROCHOT"
SEC_TYPE"0402V"
BOM_COST"FAST_PROCHOT";
"B"
$PN"2"19;
"A"
$PN"1"13;
END.
